0.01000 T01
0.01200 T02
0.01600 T03
0.02800 T04
0.03200 T05
0.03600 T06
0.05200 T07
0.08600 T08
0.09100 T09
0.22400 T010
